(kicad_pcb
	(version 20260206)
	(generator "pcbnew")
	(generator_version "10.0")
	(general
		(thickness 1.6)
		(legacy_teardrops no)
	)
	(paper "A4")
	(title_block
		(title "01162023_DA0F0TEBIF0_F0T_Expander_BD_F_brd_V02_OCP.brd")
		(comment 1 "Grand Teton / footprints 6047-6052 of 9728")
	)
	(layers
		(0 "F.Cu" signal "TOP")
		(4 "In1.Cu" signal "GND")
		(6 "In2.Cu" signal "VCC")
		(8 "In3.Cu" signal "VCC1")
		(10 "In4.Cu" signal "GND1")
		(12 "In5.Cu" signal "IN1")
		(14 "In6.Cu" signal "GND2")
		(16 "In7.Cu" signal "IN2")
		(18 "In8.Cu" signal "GND3")
		(20 "In9.Cu" signal "IN3")
		(22 "In10.Cu" signal "GND4")
		(24 "In11.Cu" signal "IN4")
		(26 "In12.Cu" signal "GND5")
		(28 "In13.Cu" signal "IN5")
		(30 "In14.Cu" signal "GND6")
		(32 "In15.Cu" signal "IN6")
		(34 "In16.Cu" signal "GND7")
		(2 "B.Cu" signal "BOTTOM")
		(9 "F.Adhes" user "F.Adhesive")
		(11 "B.Adhes" user "B.Adhesive")
		(13 "F.Paste" user "Package Geometry/Pastemask Top")
		(15 "B.Paste" user "Package Geometry/Pastemask Bottom")
		(5 "F.SilkS" user "Ref Des/Silkscreen Top")
		(7 "B.SilkS" user "Ref Des/Silkscreen Bottom")
		(1 "F.Mask" user "Board Geometry/Soldermask Top")
		(3 "B.Mask" user "Board Geometry/Soldermask Bottom")
		(17 "Dwgs.User" user "User.Drawings")
		(19 "Cmts.User" user "User.Comments")
		(21 "Eco1.User" user "User.Eco1")
		(23 "Eco2.User" user "User.Eco2")
		(25 "Edge.Cuts" user "Board Geometry/Outline")
		(27 "Margin" user)
		(31 "F.CrtYd" user "Package Geometry/Place Bound Top")
		(29 "B.CrtYd" user "Package Geometry/Place Bound Bottom")
		(35 "F.Fab" user "Ref Des/Assembly Top")
		(33 "B.Fab" user "Ref Des/Assembly Bottom")
	)
	(footprint ""
		(layer "F.Cu")
		(at 101.951536 -7.591552)
		(property "Reference" "U129"
			(at -1.265936 2.360422 0)
			(unlocked yes)
			(layer "F.SilkS")
			(effects
				(font
					(size 0.7874 0.5842)
					(thickness 0.1524)
				)
				(justify left)
			)
		)
		(property "Value" ""
			(at 0 0 0)
			(layer "F.Fab")
			(effects
				(font
					(size 1.27 1.27)
				)
			)
		)
		(duplicate_pad_numbers_are_jumpers no)
		(fp_line
			(start -1.463548 -1.549908)
			(end -0.787908 -1.549908)
			(stroke
				(width 0.1524)
				(type default)
			)
			(layer "F.SilkS")
		)
		(fp_line
			(start -1.463548 1.549908)
			(end -1.463548 -1.549908)
			(stroke
				(width 0.1524)
				(type default)
			)
			(layer "F.SilkS")
		)
		(fp_line
			(start -0.787908 -1.549908)
			(end 0 -0.762)
			(stroke
				(width 0.1524)
				(type default)
			)
			(layer "F.SilkS")
		)
		(fp_line
			(start 0 -0.762)
			(end 0.762 -1.549908)
			(stroke
				(width 0.1524)
				(type default)
			)
			(layer "F.SilkS")
		)
		(fp_line
			(start 0.762 -1.549908)
			(end 1.463548 -1.549908)
			(stroke
				(width 0.1524)
				(type default)
			)
			(layer "F.SilkS")
		)
		(fp_line
			(start 1.463548 -1.549908)
			(end 1.463548 1.549908)
			(stroke
				(width 0.1524)
				(type default)
			)
			(layer "F.SilkS")
		)
		(fp_line
			(start 1.463548 1.549908)
			(end -1.463548 1.549908)
			(stroke
				(width 0.1524)
				(type default)
			)
			(layer "F.SilkS")
		)
		(fp_poly
			(pts
				(xy -3.4798 -1.359916) (xy -2.86004 -1.050036) (xy -3.4798 -0.740156)
			)
			(stroke
				(width 0)
				(type default)
			)
			(fill yes)
			(layer "F.SilkS")
		)
		(fp_line
			(start -1.549908 -1.549908)
			(end 1.549908 -1.549908)
			(stroke
				(width 0.1)
				(type default)
			)
			(layer "F.Fab")
		)
		(fp_line
			(start -1.549908 1.549908)
			(end -1.549908 -1.549908)
			(stroke
				(width 0.1)
				(type default)
			)
			(layer "F.Fab")
		)
		(fp_line
			(start 1.549908 -1.549908)
			(end 1.549908 1.549908)
			(stroke
				(width 0.1)
				(type default)
			)
			(layer "F.Fab")
		)
		(fp_line
			(start 1.549908 1.549908)
			(end -1.549908 1.549908)
			(stroke
				(width 0.1)
				(type default)
			)
			(layer "F.Fab")
		)
		(fp_poly
			(pts
				(xy -3.4798 -1.359916) (xy -2.86004 -1.050036) (xy -3.4798 -0.740156)
			)
			(stroke
				(width 0)
				(type default)
			)
			(fill yes)
			(layer "F.Fab")
		)
		(pad "1" smd rect
			(at -2.175002 -1.050036 90)
			(size 0.6096 1.1684)
			(layers "F.Cu" "F.Mask" "F.Paste")
			(net "P3V3_SSD3")
		)
		(pad "2" smd rect
			(at -2.175002 -0.32512 90)
			(size 0.4318 1.1684)
			(layers "F.Cu" "F.Mask" "F.Paste")
			(net "SMB_ISO_SSD3_SCL")
		)
		(pad "3" smd rect
			(at -2.175002 0.32512 90)
			(size 0.4318 1.1684)
			(layers "F.Cu" "F.Mask" "F.Paste")
			(net "SMB_ISO_SSD3_SDA")
		)
		(pad "4" smd rect
			(at -2.175002 1.050036 90)
			(size 0.6096 1.1684)
			(layers "F.Cu" "F.Mask" "F.Paste")
			(net "GND")
		)
		(pad "5" smd rect
			(at 2.175002 1.050036 90)
			(size 0.6096 1.1684)
			(layers "F.Cu" "F.Mask" "F.Paste")
			(net "SMB_SSD3_ISO_EN")
		)
		(pad "6" smd rect
			(at 2.175002 0.32512 90)
			(size 0.4318 1.1684)
			(layers "F.Cu" "F.Mask" "F.Paste")
			(net "SMB_BIC_I2C9_MUX0_SSD3_R_SDA")
		)
		(pad "7" smd rect
			(at 2.175002 -0.32512 90)
			(size 0.4318 1.1684)
			(layers "F.Cu" "F.Mask" "F.Paste")
			(net "SMB_BIC_I2C9_MUX0_SSD3_R_SCL")
		)
		(pad "8" smd rect
			(at 2.175002 -1.050036 90)
			(size 0.6096 1.1684)
			(layers "F.Cu" "F.Mask" "F.Paste")
			(net "P3V3_AUX")
		)
	)
	(footprint ""
		(layer "F.Cu")
		(at 167.498522 -180.372766 180)
		(property "Reference" "R152"
			(at 0 0 180)
			(layer "F.SilkS")
			(hide yes)
			(effects
				(font
					(size 1.27 1.27)
				)
			)
		)
		(property "Value" ""
			(at 0 0 180)
			(layer "F.Fab")
			(effects
				(font
					(size 1.27 1.27)
				)
			)
		)
		(duplicate_pad_numbers_are_jumpers no)
		(fp_line
			(start 0.7874 0.4064)
			(end -0.7874 0.4064)
			(stroke
				(width 0.1524)
				(type default)
			)
			(layer "F.SilkS")
		)
		(fp_line
			(start 0.7874 -0.4064)
			(end 0.7874 0.4064)
			(stroke
				(width 0.1524)
				(type default)
			)
			(layer "F.SilkS")
		)
		(fp_line
			(start -0.7874 0.4064)
			(end -0.7874 -0.4064)
			(stroke
				(width 0.1524)
				(type default)
			)
			(layer "F.SilkS")
		)
		(fp_line
			(start -0.7874 -0.4064)
			(end 0.7874 -0.4064)
			(stroke
				(width 0.1524)
				(type default)
			)
			(layer "F.SilkS")
		)
		(fp_line
			(start 0.67945 0.3048)
			(end 0.120396 0.3048)
			(stroke
				(width 0.1)
				(type default)
			)
			(layer "F.Fab")
		)
		(fp_line
			(start 0.67945 -0.3048)
			(end 0.67945 0.3048)
			(stroke
				(width 0.1)
				(type default)
			)
			(layer "F.Fab")
		)
		(fp_line
			(start 0.12065 -0.2794)
			(end 0.12065 -0.3048)
			(stroke
				(width 0.1)
				(type default)
			)
			(layer "F.Fab")
		)
		(fp_line
			(start 0.12065 -0.3048)
			(end 0.67945 -0.3048)
			(stroke
				(width 0.1)
				(type default)
			)
			(layer "F.Fab")
		)
		(fp_line
			(start 0.120396 0.3048)
			(end 0.120396 0.2794)
			(stroke
				(width 0.1)
				(type default)
			)
			(layer "F.Fab")
		)
		(fp_line
			(start 0.120396 0.2794)
			(end -0.12065 0.2794)
			(stroke
				(width 0.1)
				(type default)
			)
			(layer "F.Fab")
		)
		(fp_line
			(start -0.12065 0.3048)
			(end -0.67945 0.3048)
			(stroke
				(width 0.1)
				(type default)
			)
			(layer "F.Fab")
		)
		(fp_line
			(start -0.12065 0.2794)
			(end -0.12065 0.3048)
			(stroke
				(width 0.1)
				(type default)
			)
			(layer "F.Fab")
		)
		(fp_line
			(start -0.12065 -0.2794)
			(end 0.12065 -0.2794)
			(stroke
				(width 0.1)
				(type default)
			)
			(layer "F.Fab")
		)
		(fp_line
			(start -0.12065 -0.305054)
			(end -0.12065 -0.2794)
			(stroke
				(width 0.1)
				(type default)
			)
			(layer "F.Fab")
		)
		(fp_line
			(start -0.67945 0.3048)
			(end -0.67945 -0.305054)
			(stroke
				(width 0.1)
				(type default)
			)
			(layer "F.Fab")
		)
		(fp_line
			(start -0.67945 -0.305054)
			(end -0.12065 -0.305054)
			(stroke
				(width 0.1)
				(type default)
			)
			(layer "F.Fab")
		)
		(pad "1" smd circle
			(at -0.40005 0 180)
			(size 0 0)
			(layers "F.Cu" "F.Mask" "F.Paste")
			(net "P3V3_AUX")
		)
		(pad "2" smd circle
			(at 0.40005 0 180)
			(size 0 0)
			(layers "F.Cu" "F.Mask" "F.Paste")
			(net "HP_NIC2_HSC_PWRGD_N")
		)
	)
	(footprint ""
		(layer "F.Cu")
		(at 453.841866 -254.5969 -90)
		(property "Reference" "C4395"
			(at 0 0 270)
			(layer "F.SilkS")
			(hide yes)
			(effects
				(font
					(size 1.27 1.27)
				)
			)
		)
		(property "Value" ""
			(at 0 0 270)
			(layer "F.Fab")
			(effects
				(font
					(size 1.27 1.27)
				)
			)
		)
		(duplicate_pad_numbers_are_jumpers no)
		(fp_line
			(start -1.2954 0.5842)
			(end -1.2954 -0.5842)
			(stroke
				(width 0.1524)
				(type default)
			)
			(layer "F.SilkS")
		)
		(fp_line
			(start 1.2954 0.5842)
			(end -1.2954 0.5842)
			(stroke
				(width 0.1524)
				(type default)
			)
			(layer "F.SilkS")
		)
		(fp_line
			(start -1.2954 -0.5842)
			(end 1.2954 -0.5842)
			(stroke
				(width 0.1524)
				(type default)
			)
			(layer "F.SilkS")
		)
		(fp_line
			(start 1.2954 -0.5842)
			(end 1.2954 0.5842)
			(stroke
				(width 0.1524)
				(type default)
			)
			(layer "F.SilkS")
		)
		(fp_line
			(start -0.8636 0.4572)
			(end -0.8636 0.4064)
			(stroke
				(width 0.1)
				(type default)
			)
			(layer "F.Fab")
		)
		(fp_line
			(start 0.8636 0.4572)
			(end -0.8636 0.4572)
			(stroke
				(width 0.1)
				(type default)
			)
			(layer "F.Fab")
		)
		(fp_line
			(start -1.1938 0.4064)
			(end -1.1938 -0.4064)
			(stroke
				(width 0.1)
				(type default)
			)
			(layer "F.Fab")
		)
		(fp_line
			(start -0.8636 0.4064)
			(end -1.1938 0.4064)
			(stroke
				(width 0.1)
				(type default)
			)
			(layer "F.Fab")
		)
		(fp_line
			(start 0.8636 0.4064)
			(end 0.8636 0.4572)
			(stroke
				(width 0.1)
				(type default)
			)
			(layer "F.Fab")
		)
		(fp_line
			(start 1.1938 0.4064)
			(end 0.8636 0.4064)
			(stroke
				(width 0.1)
				(type default)
			)
			(layer "F.Fab")
		)
		(fp_line
			(start -1.1938 -0.4064)
			(end -0.8636 -0.4064)
			(stroke
				(width 0.1)
				(type default)
			)
			(layer "F.Fab")
		)
		(fp_line
			(start -0.8636 -0.4064)
			(end -0.8636 -0.4572)
			(stroke
				(width 0.1)
				(type default)
			)
			(layer "F.Fab")
		)
		(fp_line
			(start 0.8636 -0.4064)
			(end 1.1938 -0.4064)
			(stroke
				(width 0.1)
				(type default)
			)
			(layer "F.Fab")
		)
		(fp_line
			(start 1.1938 -0.4064)
			(end 1.1938 0.4064)
			(stroke
				(width 0.1)
				(type default)
			)
			(layer "F.Fab")
		)
		(fp_line
			(start -0.8636 -0.4572)
			(end 0.8636 -0.4572)
			(stroke
				(width 0.1)
				(type default)
			)
			(layer "F.Fab")
		)
		(fp_line
			(start 0.8636 -0.4572)
			(end 0.8636 -0.4064)
			(stroke
				(width 0.1)
				(type default)
			)
			(layer "F.Fab")
		)
		(pad "1" smd rect
			(at -0.7366 0 180)
			(size 0.7112 0.8128)
			(layers "F.Cu" "F.Mask" "F.Paste")
			(net "P1V25_SERDES_VDDPLL_PEX3_C1")
		)
		(pad "2" smd rect
			(at 0.7366 0 180)
			(size 0.7112 0.8128)
			(layers "F.Cu" "F.Mask" "F.Paste")
			(net "GND")
		)
	)
	(footprint ""
		(layer "F.Cu")
		(at 319.70599 -392.063732 180)
		(property "Reference" "C4108"
			(at 0 0 180)
			(layer "F.SilkS")
			(hide yes)
			(effects
				(font
					(size 1.27 1.27)
				)
			)
		)
		(property "Value" ""
			(at 0 0 180)
			(layer "F.Fab")
			(effects
				(font
					(size 1.27 1.27)
				)
			)
		)
		(duplicate_pad_numbers_are_jumpers no)
		(fp_line
			(start 0.7874 0.4064)
			(end -0.7874 0.4064)
			(stroke
				(width 0.1524)
				(type default)
			)
			(layer "F.SilkS")
		)
		(fp_line
			(start 0.7874 -0.4064)
			(end 0.7874 0.4064)
			(stroke
				(width 0.1524)
				(type default)
			)
			(layer "F.SilkS")
		)
		(fp_line
			(start -0.7874 0.4064)
			(end -0.7874 -0.4064)
			(stroke
				(width 0.1524)
				(type default)
			)
			(layer "F.SilkS")
		)
		(fp_line
			(start -0.7874 -0.4064)
			(end 0.7874 -0.4064)
			(stroke
				(width 0.1524)
				(type default)
			)
			(layer "F.SilkS")
		)
		(fp_line
			(start 0.67945 0.3048)
			(end 0.120396 0.3048)
			(stroke
				(width 0.1)
				(type default)
			)
			(layer "F.Fab")
		)
		(fp_line
			(start 0.67945 -0.3048)
			(end 0.67945 0.3048)
			(stroke
				(width 0.1)
				(type default)
			)
			(layer "F.Fab")
		)
		(fp_line
			(start 0.12065 -0.2794)
			(end 0.12065 -0.3048)
			(stroke
				(width 0.1)
				(type default)
			)
			(layer "F.Fab")
		)
		(fp_line
			(start 0.12065 -0.3048)
			(end 0.67945 -0.3048)
			(stroke
				(width 0.1)
				(type default)
			)
			(layer "F.Fab")
		)
		(fp_line
			(start 0.120396 0.3048)
			(end 0.120396 0.2794)
			(stroke
				(width 0.1)
				(type default)
			)
			(layer "F.Fab")
		)
		(fp_line
			(start 0.120396 0.2794)
			(end -0.12065 0.2794)
			(stroke
				(width 0.1)
				(type default)
			)
			(layer "F.Fab")
		)
		(fp_line
			(start -0.12065 0.3048)
			(end -0.67945 0.3048)
			(stroke
				(width 0.1)
				(type default)
			)
			(layer "F.Fab")
		)
		(fp_line
			(start -0.12065 0.2794)
			(end -0.12065 0.3048)
			(stroke
				(width 0.1)
				(type default)
			)
			(layer "F.Fab")
		)
		(fp_line
			(start -0.12065 -0.2794)
			(end 0.12065 -0.2794)
			(stroke
				(width 0.1)
				(type default)
			)
			(layer "F.Fab")
		)
		(fp_line
			(start -0.12065 -0.305054)
			(end -0.12065 -0.2794)
			(stroke
				(width 0.1)
				(type default)
			)
			(layer "F.Fab")
		)
		(fp_line
			(start -0.67945 0.3048)
			(end -0.67945 -0.305054)
			(stroke
				(width 0.1)
				(type default)
			)
			(layer "F.Fab")
		)
		(fp_line
			(start -0.67945 -0.305054)
			(end -0.12065 -0.305054)
			(stroke
				(width 0.1)
				(type default)
			)
			(layer "F.Fab")
		)
		(pad "1" smd circle
			(at -0.40005 0 180)
			(size 0 0)
			(layers "F.Cu" "F.Mask" "F.Paste")
			(net "GND")
		)
		(pad "2" smd circle
			(at 0.40005 0 180)
			(size 0 0)
			(layers "F.Cu" "F.Mask" "F.Paste")
			(net "GPU_3V3IO_RSVD3_FFU")
		)
	)
	(footprint ""
		(layer "F.Cu")
		(at 316.066678 -52.543456 180)
		(property "Reference" "PC585"
			(at 0 0 180)
			(layer "F.SilkS")
			(hide yes)
			(effects
				(font
					(size 1.27 1.27)
				)
			)
		)
		(property "Value" ""
			(at 0 0 180)
			(layer "F.Fab")
			(effects
				(font
					(size 1.27 1.27)
				)
			)
		)
		(duplicate_pad_numbers_are_jumpers no)
		(fp_line
			(start 0.7874 0.4064)
			(end -0.7874 0.4064)
			(stroke
				(width 0.1524)
				(type default)
			)
			(layer "F.SilkS")
		)
		(fp_line
			(start 0.7874 -0.4064)
			(end 0.7874 0.4064)
			(stroke
				(width 0.1524)
				(type default)
			)
			(layer "F.SilkS")
		)
		(fp_line
			(start -0.7874 0.4064)
			(end -0.7874 -0.4064)
			(stroke
				(width 0.1524)
				(type default)
			)
			(layer "F.SilkS")
		)
		(fp_line
			(start -0.7874 -0.4064)
			(end 0.7874 -0.4064)
			(stroke
				(width 0.1524)
				(type default)
			)
			(layer "F.SilkS")
		)
		(fp_line
			(start 0.67945 0.3048)
			(end 0.120396 0.3048)
			(stroke
				(width 0.1)
				(type default)
			)
			(layer "F.Fab")
		)
		(fp_line
			(start 0.67945 -0.3048)
			(end 0.67945 0.3048)
			(stroke
				(width 0.1)
				(type default)
			)
			(layer "F.Fab")
		)
		(fp_line
			(start 0.12065 -0.2794)
			(end 0.12065 -0.3048)
			(stroke
				(width 0.1)
				(type default)
			)
			(layer "F.Fab")
		)
		(fp_line
			(start 0.12065 -0.3048)
			(end 0.67945 -0.3048)
			(stroke
				(width 0.1)
				(type default)
			)
			(layer "F.Fab")
		)
		(fp_line
			(start 0.120396 0.3048)
			(end 0.120396 0.2794)
			(stroke
				(width 0.1)
				(type default)
			)
			(layer "F.Fab")
		)
		(fp_line
			(start 0.120396 0.2794)
			(end -0.12065 0.2794)
			(stroke
				(width 0.1)
				(type default)
			)
			(layer "F.Fab")
		)
		(fp_line
			(start -0.12065 0.3048)
			(end -0.67945 0.3048)
			(stroke
				(width 0.1)
				(type default)
			)
			(layer "F.Fab")
		)
		(fp_line
			(start -0.12065 0.2794)
			(end -0.12065 0.3048)
			(stroke
				(width 0.1)
				(type default)
			)
			(layer "F.Fab")
		)
		(fp_line
			(start -0.12065 -0.2794)
			(end 0.12065 -0.2794)
			(stroke
				(width 0.1)
				(type default)
			)
			(layer "F.Fab")
		)
		(fp_line
			(start -0.12065 -0.305054)
			(end -0.12065 -0.2794)
			(stroke
				(width 0.1)
				(type default)
			)
			(layer "F.Fab")
		)
		(fp_line
			(start -0.67945 0.3048)
			(end -0.67945 -0.305054)
			(stroke
				(width 0.1)
				(type default)
			)
			(layer "F.Fab")
		)
		(fp_line
			(start -0.67945 -0.305054)
			(end -0.12065 -0.305054)
			(stroke
				(width 0.1)
				(type default)
			)
			(layer "F.Fab")
		)
		(pad "1" smd circle
			(at -0.40005 0 180)
			(size 0 0)
			(layers "F.Cu" "F.Mask" "F.Paste")
			(net "P3V3_SSD11")
		)
		(pad "2" smd circle
			(at 0.40005 0 180)
			(size 0 0)
			(layers "F.Cu" "F.Mask" "F.Paste")
			(net "GND")
		)
	)
	(footprint ""
		(layer "F.Cu")
		(at 363.474 -199.771)
		(property "Reference" "R4661"
			(at 0 0 0)
			(layer "F.SilkS")
			(hide yes)
			(effects
				(font
					(size 1.27 1.27)
				)
			)
		)
		(property "Value" ""
			(at 0 0 0)
			(layer "F.Fab")
			(effects
				(font
					(size 1.27 1.27)
				)
			)
		)
		(duplicate_pad_numbers_are_jumpers no)
		(fp_line
			(start -0.7874 -0.4064)
			(end 0.7874 -0.4064)
			(stroke
				(width 0.1524)
				(type default)
			)
			(layer "F.SilkS")
		)
		(fp_line
			(start -0.7874 0.4064)
			(end -0.7874 -0.4064)
			(stroke
				(width 0.1524)
				(type default)
			)
			(layer "F.SilkS")
		)
		(fp_line
			(start 0.7874 -0.4064)
			(end 0.7874 0.4064)
			(stroke
				(width 0.1524)
				(type default)
			)
			(layer "F.SilkS")
		)
		(fp_line
			(start 0.7874 0.4064)
			(end -0.7874 0.4064)
			(stroke
				(width 0.1524)
				(type default)
			)
			(layer "F.SilkS")
		)
		(fp_line
			(start -0.67945 -0.305054)
			(end -0.12065 -0.305054)
			(stroke
				(width 0.1)
				(type default)
			)
			(layer "F.Fab")
		)
		(fp_line
			(start -0.67945 0.3048)
			(end -0.67945 -0.305054)
			(stroke
				(width 0.1)
				(type default)
			)
			(layer "F.Fab")
		)
		(fp_line
			(start -0.12065 -0.305054)
			(end -0.12065 -0.2794)
			(stroke
				(width 0.1)
				(type default)
			)
			(layer "F.Fab")
		)
		(fp_line
			(start -0.12065 -0.2794)
			(end 0.12065 -0.2794)
			(stroke
				(width 0.1)
				(type default)
			)
			(layer "F.Fab")
		)
		(fp_line
			(start -0.12065 0.2794)
			(end -0.12065 0.3048)
			(stroke
				(width 0.1)
				(type default)
			)
			(layer "F.Fab")
		)
		(fp_line
			(start -0.12065 0.3048)
			(end -0.67945 0.3048)
			(stroke
				(width 0.1)
				(type default)
			)
			(layer "F.Fab")
		)
		(fp_line
			(start 0.120396 0.2794)
			(end -0.12065 0.2794)
			(stroke
				(width 0.1)
				(type default)
			)
			(layer "F.Fab")
		)
		(fp_line
			(start 0.120396 0.3048)
			(end 0.120396 0.2794)
			(stroke
				(width 0.1)
				(type default)
			)
			(layer "F.Fab")
		)
		(fp_line
			(start 0.12065 -0.3048)
			(end 0.67945 -0.3048)
			(stroke
				(width 0.1)
				(type default)
			)
			(layer "F.Fab")
		)
		(fp_line
			(start 0.12065 -0.2794)
			(end 0.12065 -0.3048)
			(stroke
				(width 0.1)
				(type default)
			)
			(layer "F.Fab")
		)
		(fp_line
			(start 0.67945 -0.3048)
			(end 0.67945 0.3048)
			(stroke
				(width 0.1)
				(type default)
			)
			(layer "F.Fab")
		)
		(fp_line
			(start 0.67945 0.3048)
			(end 0.120396 0.3048)
			(stroke
				(width 0.1)
				(type default)
			)
			(layer "F.Fab")
		)
		(pad "1" smd circle
			(at -0.40005 0)
			(size 0 0)
			(layers "F.Cu" "F.Mask" "F.Paste")
			(net "P3V3_AUX")
		)
		(pad "2" smd circle
			(at 0.40005 0)
			(size 0 0)
			(layers "F.Cu" "F.Mask" "F.Paste")
			(net "SSD4_PEX_PWR_EN_R")
		)
	)
)
